(kicad_pcb
	(version 20260206)
	(generator "pcbnew")
	(generator_version "10.0")
	(general
		(thickness 1.6)
		(legacy_teardrops no)
	)
	(paper "A4")
	(title_block
		(title "dpb — 14545-sa.0730WZS0815.brd")
		(comment 1 "Honey Badger (Wiwynn) / footprints 273-279 of 1066")
	)
	(layers
		(0 "F.Cu" signal "TOP")
		(4 "In1.Cu" signal "L2GND")
		(6 "In2.Cu" signal "L3")
		(8 "In3.Cu" signal "L4VCC")
		(10 "In4.Cu" signal "L5VCC")
		(12 "In5.Cu" signal "L6")
		(14 "In6.Cu" signal "L7GND")
		(2 "B.Cu" signal "BOTTOM")
		(9 "F.Adhes" user "F.Adhesive")
		(11 "B.Adhes" user "B.Adhesive")
		(13 "F.Paste" user "Package Geometry/Pastemask Top")
		(15 "B.Paste" user "Package Geometry/Pastemask Bottom")
		(5 "F.SilkS" user "Ref Des/Silkscreen Top")
		(7 "B.SilkS" user "Ref Des/Silkscreen Bottom")
		(1 "F.Mask" user "Board Geometry/Soldermask Top")
		(3 "B.Mask" user "Board Geometry/Soldermask Bottom")
		(17 "Dwgs.User" user "User.Drawings")
		(19 "Cmts.User" user "User.Comments")
		(21 "Eco1.User" user "User.Eco1")
		(23 "Eco2.User" user "User.Eco2")
		(25 "Edge.Cuts" user "Board Geometry/Outline")
		(27 "Margin" user)
		(31 "F.CrtYd" user "Package Geometry/Place Bound Top")
		(29 "B.CrtYd" user "Package Geometry/Place Bound Bottom")
		(35 "F.Fab" user "Ref Des/Assembly Top")
		(33 "B.Fab" user "Ref Des/Assembly Bottom")
	)
	(footprint ""
		(layer "F.Cu")
		(at 77.469746 -395.8717 -90)
		(property "Reference" "R197"
			(at 0 0 270)
			(layer "F.SilkS")
			(hide yes)
			(effects
				(font
					(size 1.27 1.27)
				)
			)
		)
		(property "Value" "0R2J-2-GP"
			(at 0.064008 -3.993896 270)
			(unlocked yes)
			(layer "F.Fab")
			(hide yes)
			(effects
				(font
					(size 1.016 1.016)
					(thickness 0.1524)
				)
			)
		)
		(property "Device Type" "R402H16"
			(at 0.064008 -5.517896 270)
			(unlocked yes)
			(layer "F.Fab")
			(hide yes)
			(effects
				(font
					(size 1.016 1.016)
					(thickness 0.1524)
				)
			)
		)
		(duplicate_pad_numbers_are_jumpers no)
		(fp_line
			(start -0.508 -0.9398)
			(end -0.508 0.9398)
			(stroke
				(width 0.1524)
				(type default)
			)
			(layer "F.SilkS")
		)
		(fp_line
			(start 0.508 -0.9398)
			(end -0.508 -0.9398)
			(stroke
				(width 0.1524)
				(type default)
			)
			(layer "F.SilkS")
		)
		(fp_rect
			(start -0.508 0.9398)
			(end 0.508 -0.9398)
			(stroke
				(width 0)
				(type default)
			)
			(fill no)
			(layer "F.CrtYd")
		)
		(fp_rect
			(start -0.508 0.9398)
			(end 0.508 -0.9398)
			(stroke
				(width 0)
				(type default)
			)
			(fill no)
			(layer "F.Fab")
		)
		(pad "1" smd custom
			(at 0 -0.4445 270)
			(size 0.1397 0.1397)
			(layers "F.Cu" "F.Mask" "F.Paste")
			(net "DRIVE_PWR6")
			(options
				(clearance outline)
				(anchor circle)
			)
			(primitives
				(gr_poly
					(pts
						(arc
							(start -0.1778 -0.2794)
							(mid -0.249642 -0.249642)
							(end -0.2794 -0.1778)
						)
						(arc
							(start -0.2794 0.1778)
							(mid -0.249642 0.249642)
							(end -0.1778 0.2794)
						)
						(arc
							(start 0.1778 0.2794)
							(mid 0.249642 0.249642)
							(end 0.2794 0.1778)
						)
						(arc
							(start 0.2794 -0.1778)
							(mid 0.249642 -0.249642)
							(end 0.1778 -0.2794)
						)
					)
					(width 0)
					(fill yes)
				)
			)
		)
		(pad "2" smd custom
			(at 0 0.4445 270)
			(size 0.1397 0.1397)
			(layers "F.Cu" "F.Mask" "F.Paste")
			(net "SW_PWR_HDD6")
			(options
				(clearance outline)
				(anchor circle)
			)
			(primitives
				(gr_poly
					(pts
						(arc
							(start -0.1778 -0.2794)
							(mid -0.249642 -0.249642)
							(end -0.2794 -0.1778)
						)
						(arc
							(start -0.2794 0.1778)
							(mid -0.249642 0.249642)
							(end -0.1778 0.2794)
						)
						(arc
							(start 0.1778 0.2794)
							(mid 0.249642 0.249642)
							(end 0.2794 0.1778)
						)
						(arc
							(start 0.2794 -0.1778)
							(mid 0.249642 -0.249642)
							(end 0.1778 -0.2794)
						)
					)
					(width 0)
					(fill yes)
				)
			)
		)
	)
	(footprint ""
		(layer "F.Cu")
		(at 43.865546 -133.3119 -90)
		(property "Reference" "R325"
			(at 0 0 270)
			(layer "F.SilkS")
			(hide yes)
			(effects
				(font
					(size 1.27 1.27)
				)
			)
		)
		(property "Value" "4K7R2J-2-GP"
			(at 0.064008 -3.993896 270)
			(unlocked yes)
			(layer "F.Fab")
			(hide yes)
			(effects
				(font
					(size 1.016 1.016)
					(thickness 0.1524)
				)
			)
		)
		(property "Device Type" "R402H16"
			(at 0.064008 -5.517896 270)
			(unlocked yes)
			(layer "F.Fab")
			(hide yes)
			(effects
				(font
					(size 1.016 1.016)
					(thickness 0.1524)
				)
			)
		)
		(duplicate_pad_numbers_are_jumpers no)
		(fp_line
			(start -0.508 -0.9398)
			(end -0.508 0.9398)
			(stroke
				(width 0.1524)
				(type default)
			)
			(layer "F.SilkS")
		)
		(fp_line
			(start 0.508 -0.9398)
			(end -0.508 -0.9398)
			(stroke
				(width 0.1524)
				(type default)
			)
			(layer "F.SilkS")
		)
		(fp_rect
			(start -0.508 0.9398)
			(end 0.508 -0.9398)
			(stroke
				(width 0)
				(type default)
			)
			(fill no)
			(layer "F.CrtYd")
		)
		(fp_rect
			(start -0.508 0.9398)
			(end 0.508 -0.9398)
			(stroke
				(width 0)
				(type default)
			)
			(fill no)
			(layer "F.Fab")
		)
		(pad "1" smd custom
			(at 0 -0.4445 270)
			(size 0.1397 0.1397)
			(layers "F.Cu" "F.Mask" "F.Paste")
			(net "I2C_B_TMP2_A0")
			(options
				(clearance outline)
				(anchor circle)
			)
			(primitives
				(gr_poly
					(pts
						(arc
							(start -0.1778 -0.2794)
							(mid -0.249642 -0.249642)
							(end -0.2794 -0.1778)
						)
						(arc
							(start -0.2794 0.1778)
							(mid -0.249642 0.249642)
							(end -0.1778 0.2794)
						)
						(arc
							(start 0.1778 0.2794)
							(mid 0.249642 0.249642)
							(end 0.2794 0.1778)
						)
						(arc
							(start 0.2794 -0.1778)
							(mid 0.249642 -0.249642)
							(end 0.1778 -0.2794)
						)
					)
					(width 0)
					(fill yes)
				)
			)
		)
		(pad "2" smd custom
			(at 0 0.4445 270)
			(size 0.1397 0.1397)
			(layers "F.Cu" "F.Mask" "F.Paste")
			(net "GND")
			(options
				(clearance outline)
				(anchor circle)
			)
			(primitives
				(gr_poly
					(pts
						(arc
							(start -0.1778 -0.2794)
							(mid -0.249642 -0.249642)
							(end -0.2794 -0.1778)
						)
						(arc
							(start -0.2794 0.1778)
							(mid -0.249642 0.249642)
							(end -0.1778 0.2794)
						)
						(arc
							(start 0.1778 0.2794)
							(mid 0.249642 0.249642)
							(end 0.2794 0.1778)
						)
						(arc
							(start 0.2794 -0.1778)
							(mid 0.249642 -0.249642)
							(end 0.1778 -0.2794)
						)
					)
					(width 0)
					(fill yes)
				)
			)
		)
	)
	(footprint ""
		(layer "F.Cu")
		(at 215.3412 -377.9774 -90)
		(property "Reference" "R353"
			(at 0 0 270)
			(layer "F.SilkS")
			(hide yes)
			(effects
				(font
					(size 1.27 1.27)
				)
			)
		)
		(property "Value" "0R2J-2-GP"
			(at 0.064008 -3.993896 270)
			(unlocked yes)
			(layer "F.Fab")
			(hide yes)
			(effects
				(font
					(size 1.016 1.016)
					(thickness 0.1524)
				)
			)
		)
		(property "Device Type" "R402H16"
			(at 0.064008 -5.517896 270)
			(unlocked yes)
			(layer "F.Fab")
			(hide yes)
			(effects
				(font
					(size 1.016 1.016)
					(thickness 0.1524)
				)
			)
		)
		(duplicate_pad_numbers_are_jumpers no)
		(fp_line
			(start -0.508 -0.9398)
			(end -0.508 0.9398)
			(stroke
				(width 0.1524)
				(type default)
			)
			(layer "F.SilkS")
		)
		(fp_line
			(start 0.508 -0.9398)
			(end -0.508 -0.9398)
			(stroke
				(width 0.1524)
				(type default)
			)
			(layer "F.SilkS")
		)
		(fp_rect
			(start -0.508 0.9398)
			(end 0.508 -0.9398)
			(stroke
				(width 0)
				(type default)
			)
			(fill no)
			(layer "F.CrtYd")
		)
		(fp_rect
			(start -0.508 0.9398)
			(end 0.508 -0.9398)
			(stroke
				(width 0)
				(type default)
			)
			(fill no)
			(layer "F.Fab")
		)
		(pad "1" smd custom
			(at 0 -0.4445 270)
			(size 0.1397 0.1397)
			(layers "F.Cu" "F.Mask" "F.Paste")
			(net "HDD_PRSNT_NET1")
			(options
				(clearance outline)
				(anchor circle)
			)
			(primitives
				(gr_poly
					(pts
						(arc
							(start -0.1778 -0.2794)
							(mid -0.249642 -0.249642)
							(end -0.2794 -0.1778)
						)
						(arc
							(start -0.2794 0.1778)
							(mid -0.249642 0.249642)
							(end -0.1778 0.2794)
						)
						(arc
							(start 0.1778 0.2794)
							(mid 0.249642 0.249642)
							(end 0.2794 0.1778)
						)
						(arc
							(start 0.2794 -0.1778)
							(mid 0.249642 -0.249642)
							(end 0.1778 -0.2794)
						)
					)
					(width 0)
					(fill yes)
				)
			)
		)
		(pad "2" smd custom
			(at 0 0.4445 270)
			(size 0.1397 0.1397)
			(layers "F.Cu" "F.Mask" "F.Paste")
			(net "HDD1_LED_B")
			(options
				(clearance outline)
				(anchor circle)
			)
			(primitives
				(gr_poly
					(pts
						(arc
							(start -0.1778 -0.2794)
							(mid -0.249642 -0.249642)
							(end -0.2794 -0.1778)
						)
						(arc
							(start -0.2794 0.1778)
							(mid -0.249642 0.249642)
							(end -0.1778 0.2794)
						)
						(arc
							(start 0.1778 0.2794)
							(mid 0.249642 0.249642)
							(end 0.2794 0.1778)
						)
						(arc
							(start 0.2794 -0.1778)
							(mid 0.249642 -0.249642)
							(end 0.1778 -0.2794)
						)
					)
					(width 0)
					(fill yes)
				)
			)
		)
	)
	(footprint ""
		(layer "F.Cu")
		(at 17.500092 -258.83997)
		(property "Reference" "LED13"
			(at 0 0 0)
			(layer "F.SilkS")
			(hide yes)
			(effects
				(font
					(size 1.27 1.27)
				)
			)
		)
		(property "Value" "LED-RB-4-GP"
			(at 5.88899 1.80848 0)
			(unlocked yes)
			(layer "F.Fab")
			(hide yes)
			(effects
				(font
					(size 1.016 1.016)
					(thickness 0.1524)
				)
			)
		)
		(property "Device Type" "LED1613-4PH20"
			(at 5.88899 0.28448 0)
			(unlocked yes)
			(layer "F.Fab")
			(hide yes)
			(effects
				(font
					(size 1.016 1.016)
					(thickness 0.1524)
				)
			)
		)
		(duplicate_pad_numbers_are_jumpers no)
		(fp_line
			(start -1.4478 -0.9652)
			(end 1.4478 -0.9652)
			(stroke
				(width 0.1524)
				(type default)
			)
			(layer "F.SilkS")
		)
		(fp_line
			(start -1.4478 0.9652)
			(end -1.4478 -0.9652)
			(stroke
				(width 0.1524)
				(type default)
			)
			(layer "F.SilkS")
		)
		(fp_line
			(start -1.4478 0.9652)
			(end -1.4478 -0.9652)
			(stroke
				(width 0.508)
				(type default)
			)
			(layer "F.SilkS")
		)
		(fp_line
			(start 1.4478 -0.9652)
			(end 1.4478 0.9652)
			(stroke
				(width 0.1524)
				(type default)
			)
			(layer "F.SilkS")
		)
		(fp_line
			(start 1.4478 0.9652)
			(end -1.4478 0.9652)
			(stroke
				(width 0.1524)
				(type default)
			)
			(layer "F.SilkS")
		)
		(fp_rect
			(start -0.8001 0.6477)
			(end 0.8001 -0.6477)
			(stroke
				(width 0)
				(type default)
			)
			(fill no)
			(layer "F.CrtYd")
		)
		(fp_poly
			(pts
				(xy -1.7018 1.2192) (xy -1.7018 -0.06223) (xy -0.8001 -0.06223) (xy -0.8001 0.6477) (xy 0.8001 0.6477)
				(xy 0.8001 -0.6477) (xy -0.8001 -0.6477) (xy -0.8001 -0.0635) (xy -1.7018 -0.0635) (xy -1.7018 -1.2192)
				(xy 1.7018 -1.2192) (xy 1.7018 1.2192)
			)
			(stroke
				(width 0)
				(type default)
			)
			(fill no)
			(layer "F.CrtYd")
		)
		(fp_rect
			(start -1.7018 1.2192)
			(end 1.7018 -1.2192)
			(stroke
				(width 0)
				(type default)
			)
			(fill no)
			(layer "F.Fab")
		)
		(pad "1" smd rect
			(at -0.73025 0.4064)
			(size 0.9144 0.6096)
			(layers "F.Cu" "F.Mask" "F.Paste")
			(net "DRV_ACT_NET12")
		)
		(pad "2" smd rect
			(at -0.73025 -0.4064)
			(size 0.9144 0.6096)
			(layers "F.Cu" "F.Mask" "F.Paste")
			(net "FLT_NET_HDD12")
		)
		(pad "3" smd rect
			(at 0.73025 -0.4064)
			(size 0.9144 0.6096)
			(layers "F.Cu" "F.Mask" "F.Paste")
			(net "FLT_HDD12")
		)
		(pad "4" smd rect
			(at 0.73025 0.4064)
			(size 0.9144 0.6096)
			(layers "F.Cu" "F.Mask" "F.Paste")
			(net "DRV_ACT_12")
		)
	)
	(footprint ""
		(layer "F.Cu")
		(at 58.895488 -23.513288 -90)
		(property "Reference" "PR28"
			(at 0 0 270)
			(layer "F.SilkS")
			(hide yes)
			(effects
				(font
					(size 1.27 1.27)
				)
			)
		)
		(property "Value" "0R2J-2-GP"
			(at 0.064008 -3.993896 270)
			(unlocked yes)
			(layer "F.Fab")
			(hide yes)
			(effects
				(font
					(size 1.016 1.016)
					(thickness 0.1524)
				)
			)
		)
		(property "Device Type" "R402H16"
			(at 0.064008 -5.517896 270)
			(unlocked yes)
			(layer "F.Fab")
			(hide yes)
			(effects
				(font
					(size 1.016 1.016)
					(thickness 0.1524)
				)
			)
		)
		(duplicate_pad_numbers_are_jumpers no)
		(fp_line
			(start -0.508 -0.9398)
			(end -0.508 0.9398)
			(stroke
				(width 0.1524)
				(type default)
			)
			(layer "F.SilkS")
		)
		(fp_line
			(start 0.508 -0.9398)
			(end -0.508 -0.9398)
			(stroke
				(width 0.1524)
				(type default)
			)
			(layer "F.SilkS")
		)
		(fp_rect
			(start -0.508 0.9398)
			(end 0.508 -0.9398)
			(stroke
				(width 0)
				(type default)
			)
			(fill no)
			(layer "F.CrtYd")
		)
		(fp_rect
			(start -0.508 0.9398)
			(end 0.508 -0.9398)
			(stroke
				(width 0)
				(type default)
			)
			(fill no)
			(layer "F.Fab")
		)
		(pad "1" smd custom
			(at 0 -0.4445 270)
			(size 0.1397 0.1397)
			(layers "F.Cu" "F.Mask" "F.Paste")
			(net "P5VB_MODE_PG")
			(options
				(clearance outline)
				(anchor circle)
			)
			(primitives
				(gr_poly
					(pts
						(arc
							(start -0.1778 -0.2794)
							(mid -0.249642 -0.249642)
							(end -0.2794 -0.1778)
						)
						(arc
							(start -0.2794 0.1778)
							(mid -0.249642 0.249642)
							(end -0.1778 0.2794)
						)
						(arc
							(start 0.1778 0.2794)
							(mid 0.249642 0.249642)
							(end 0.2794 0.1778)
						)
						(arc
							(start 0.2794 -0.1778)
							(mid 0.249642 -0.249642)
							(end 0.1778 -0.2794)
						)
					)
					(width 0)
					(fill yes)
				)
			)
		)
		(pad "2" smd custom
			(at 0 0.4445 270)
			(size 0.1397 0.1397)
			(layers "F.Cu" "F.Mask" "F.Paste")
			(net "P5VB_MODE")
			(options
				(clearance outline)
				(anchor circle)
			)
			(primitives
				(gr_poly
					(pts
						(arc
							(start -0.1778 -0.2794)
							(mid -0.249642 -0.249642)
							(end -0.2794 -0.1778)
						)
						(arc
							(start -0.2794 0.1778)
							(mid -0.249642 0.249642)
							(end -0.1778 0.2794)
						)
						(arc
							(start 0.1778 0.2794)
							(mid 0.249642 0.249642)
							(end 0.2794 0.1778)
						)
						(arc
							(start 0.2794 -0.1778)
							(mid 0.249642 -0.249642)
							(end 0.1778 -0.2794)
						)
					)
					(width 0)
					(fill yes)
				)
			)
		)
	)
	(footprint ""
		(layer "F.Cu")
		(at 164.858446 -460.409036)
		(property "Reference" "R362"
			(at 0 0 0)
			(layer "F.SilkS")
			(hide yes)
			(effects
				(font
					(size 1.27 1.27)
				)
			)
		)
		(property "Value" "4K7R2F-GP"
			(at 0.064008 -3.993896 0)
			(unlocked yes)
			(layer "F.Fab")
			(hide yes)
			(effects
				(font
					(size 1.016 1.016)
					(thickness 0.1524)
				)
			)
		)
		(property "Device Type" "R402H16"
			(at 0.064008 -5.517896 0)
			(unlocked yes)
			(layer "F.Fab")
			(hide yes)
			(effects
				(font
					(size 1.016 1.016)
					(thickness 0.1524)
				)
			)
		)
		(duplicate_pad_numbers_are_jumpers no)
		(fp_line
			(start -0.508 -0.9398)
			(end -0.508 0.9398)
			(stroke
				(width 0.1524)
				(type default)
			)
			(layer "F.SilkS")
		)
		(fp_line
			(start 0.508 -0.9398)
			(end -0.508 -0.9398)
			(stroke
				(width 0.1524)
				(type default)
			)
			(layer "F.SilkS")
		)
		(fp_rect
			(start -0.508 0.9398)
			(end 0.508 -0.9398)
			(stroke
				(width 0)
				(type default)
			)
			(fill no)
			(layer "F.CrtYd")
		)
		(fp_rect
			(start -0.508 0.9398)
			(end 0.508 -0.9398)
			(stroke
				(width 0)
				(type default)
			)
			(fill no)
			(layer "F.Fab")
		)
		(pad "1" smd custom
			(at 0 -0.4445)
			(size 0.1397 0.1397)
			(layers "F.Cu" "F.Mask" "F.Paste")
			(net "P3V3")
			(options
				(clearance outline)
				(anchor circle)
			)
			(primitives
				(gr_poly
					(pts
						(arc
							(start -0.1778 -0.2794)
							(mid -0.249642 -0.249642)
							(end -0.2794 -0.1778)
						)
						(arc
							(start -0.2794 0.1778)
							(mid -0.249642 0.249642)
							(end -0.1778 0.2794)
						)
						(arc
							(start 0.1778 0.2794)
							(mid 0.249642 0.249642)
							(end 0.2794 0.1778)
						)
						(arc
							(start 0.2794 -0.1778)
							(mid 0.249642 -0.249642)
							(end 0.1778 -0.2794)
						)
					)
					(width 0)
					(fill yes)
				)
			)
		)
		(pad "2" smd custom
			(at 0 0.4445)
			(size 0.1397 0.1397)
			(layers "F.Cu" "F.Mask" "F.Paste")
			(net "VOL_SEN_ALERT")
			(options
				(clearance outline)
				(anchor circle)
			)
			(primitives
				(gr_poly
					(pts
						(arc
							(start -0.1778 -0.2794)
							(mid -0.249642 -0.249642)
							(end -0.2794 -0.1778)
						)
						(arc
							(start -0.2794 0.1778)
							(mid -0.249642 0.249642)
							(end -0.1778 0.2794)
						)
						(arc
							(start 0.1778 0.2794)
							(mid 0.249642 0.249642)
							(end 0.2794 0.1778)
						)
						(arc
							(start 0.2794 -0.1778)
							(mid 0.249642 -0.249642)
							(end 0.1778 -0.2794)
						)
					)
					(width 0)
					(fill yes)
				)
			)
		)
	)
	(footprint ""
		(layer "F.Cu")
		(at 17.500092 -464.840066)
		(property "Reference" "LED11"
			(at 0 0 0)
			(layer "F.SilkS")
			(hide yes)
			(effects
				(font
					(size 1.27 1.27)
				)
			)
		)
		(property "Value" "LED-RB-4-GP"
			(at 5.88899 1.80848 0)
			(unlocked yes)
			(layer "F.Fab")
			(hide yes)
			(effects
				(font
					(size 1.016 1.016)
					(thickness 0.1524)
				)
			)
		)
		(property "Device Type" "LED1613-4PH20"
			(at 5.88899 0.28448 0)
			(unlocked yes)
			(layer "F.Fab")
			(hide yes)
			(effects
				(font
					(size 1.016 1.016)
					(thickness 0.1524)
				)
			)
		)
		(duplicate_pad_numbers_are_jumpers no)
		(fp_line
			(start -1.4478 -0.9652)
			(end 1.4478 -0.9652)
			(stroke
				(width 0.1524)
				(type default)
			)
			(layer "F.SilkS")
		)
		(fp_line
			(start -1.4478 0.9652)
			(end -1.4478 -0.9652)
			(stroke
				(width 0.1524)
				(type default)
			)
			(layer "F.SilkS")
		)
		(fp_line
			(start -1.4478 0.9652)
			(end -1.4478 -0.9652)
			(stroke
				(width 0.508)
				(type default)
			)
			(layer "F.SilkS")
		)
		(fp_line
			(start 1.4478 -0.9652)
			(end 1.4478 0.9652)
			(stroke
				(width 0.1524)
				(type default)
			)
			(layer "F.SilkS")
		)
		(fp_line
			(start 1.4478 0.9652)
			(end -1.4478 0.9652)
			(stroke
				(width 0.1524)
				(type default)
			)
			(layer "F.SilkS")
		)
		(fp_rect
			(start -0.8001 0.6477)
			(end 0.8001 -0.6477)
			(stroke
				(width 0)
				(type default)
			)
			(fill no)
			(layer "F.CrtYd")
		)
		(fp_poly
			(pts
				(xy -1.7018 1.2192) (xy -1.7018 -0.06223) (xy -0.8001 -0.06223) (xy -0.8001 0.6477) (xy 0.8001 0.6477)
				(xy 0.8001 -0.6477) (xy -0.8001 -0.6477) (xy -0.8001 -0.0635) (xy -1.7018 -0.0635) (xy -1.7018 -1.2192)
				(xy 1.7018 -1.2192) (xy 1.7018 1.2192)
			)
			(stroke
				(width 0)
				(type default)
			)
			(fill no)
			(layer "F.CrtYd")
		)
		(fp_rect
			(start -1.7018 1.2192)
			(end 1.7018 -1.2192)
			(stroke
				(width 0)
				(type default)
			)
			(fill no)
			(layer "F.Fab")
		)
		(pad "1" smd rect
			(at -0.73025 0.4064)
			(size 0.9144 0.6096)
			(layers "F.Cu" "F.Mask" "F.Paste")
			(net "DRV_ACT_NET10")
		)
		(pad "2" smd rect
			(at -0.73025 -0.4064)
			(size 0.9144 0.6096)
			(layers "F.Cu" "F.Mask" "F.Paste")
			(net "FLT_NET_HDD10")
		)
		(pad "3" smd rect
			(at 0.73025 -0.4064)
			(size 0.9144 0.6096)
			(layers "F.Cu" "F.Mask" "F.Paste")
			(net "FLT_HDD10")
		)
		(pad "4" smd rect
			(at 0.73025 0.4064)
			(size 0.9144 0.6096)
			(layers "F.Cu" "F.Mask" "F.Paste")
			(net "DRV_ACT_10")
		)
	)
)
